(kicad_pcb
	(version 20260206)
	(generator "pcbnew")
	(generator_version "10.0")
	(general
		(thickness 1.6)
		(legacy_teardrops no)
	)
	(paper "A4")
	(title_block
		(title "04192023_DAF0TMB3IC0_F0TG_MB_C_brd_V02_OCP.brd")
		(comment 1 "Grand Teton / footprint 4346 of 8354 (U6010), pads 112-223 of 354")
	)
	(layers
		(0 "F.Cu" signal "TOP")
		(4 "In1.Cu" signal "GND")
		(6 "In2.Cu" signal "IN1")
		(8 "In3.Cu" signal "GND1")
		(10 "In4.Cu" signal "IN2")
		(12 "In5.Cu" signal "GND2")
		(14 "In6.Cu" signal "IN3")
		(16 "In7.Cu" signal "GND3")
		(18 "In8.Cu" signal "VCC")
		(20 "In9.Cu" signal "VCC1")
		(22 "In10.Cu" signal "GND4")
		(24 "In11.Cu" signal "IN4")
		(26 "In12.Cu" signal "GND5")
		(28 "In13.Cu" signal "IN5")
		(30 "In14.Cu" signal "GND6")
		(32 "In15.Cu" signal "IN6")
		(34 "In16.Cu" signal "GND7")
		(2 "B.Cu" signal "BOTTOM")
		(9 "F.Adhes" user "F.Adhesive")
		(11 "B.Adhes" user "B.Adhesive")
		(13 "F.Paste" user "Package Geometry/Pastemask Top")
		(15 "B.Paste" user "Package Geometry/Pastemask Bottom")
		(5 "F.SilkS" user "Ref Des/Silkscreen Top")
		(7 "B.SilkS" user "Ref Des/Silkscreen Bottom")
		(1 "F.Mask" user "Board Geometry/Soldermask Top")
		(3 "B.Mask" user "Board Geometry/Soldermask Bottom")
		(17 "Dwgs.User" user "User.Drawings")
		(19 "Cmts.User" user "User.Comments")
		(21 "Eco1.User" user "User.Eco1")
		(23 "Eco2.User" user "User.Eco2")
		(25 "Edge.Cuts" user "Board Geometry/Outline")
		(27 "Margin" user)
		(31 "F.CrtYd" user "Package Geometry/Place Bound Top")
		(29 "B.CrtYd" user "Package Geometry/Place Bound Bottom")
		(35 "F.Fab" user "Ref Des/Assembly Top")
		(33 "B.Fab" user "Ref Des/Assembly Bottom")
	)
	(footprint ""
		(layer "F.Cu")
		(at 312.467752 -395.724634)
		(property "Reference" "U6010"
			(at -6.426454 -7.380224 0)
			(unlocked yes)
			(layer "F.SilkS")
			(effects
				(font
					(size 0.7874 0.5842)
					(thickness 0.1524)
				)
				(justify left)
			)
		)
		(property "Value" ""
			(at 0 0 0)
			(layer "F.Fab")
			(effects
				(font
					(size 1.27 1.27)
				)
			)
		)
		(duplicate_pad_numbers_are_jumpers no)
		(pad "BV32" smd circle
			(at 1.20269 2.724912)
			(size 0.381 0.381)
			(layers "F.Cu" "F.Mask" "F.Paste")
			(net "GND")
		)
		(pad "BW2" smd circle
			(at 1.150112 -3.41884)
			(size 0.3048 0.3048)
			(layers "F.Cu" "F.Mask" "F.Paste")
			(net "GND")
		)
		(pad "BW34" smd circle
			(at 1.150112 3.420364)
			(size 0.3048 0.3048)
			(layers "F.Cu" "F.Mask" "F.Paste")
			(net "GND")
		)
		(pad "BY1" smd oval
			(at 0.849884 -3.938524)
			(size 0.254 0.3302)
			(layers "F.Cu" "F.Mask" "F.Paste")
			(net "GND")
		)
		(pad "BY35" smd oval
			(at 0.849884 3.940048)
			(size 0.254 0.3302)
			(layers "F.Cu" "F.Mask" "F.Paste")
			(net "GND")
		)
		(pad "C2" smd circle
			(at 10.750042 -3.41884)
			(size 0.3048 0.3048)
			(layers "F.Cu" "F.Mask" "F.Paste")
			(net "NCF_CPU0_P0_GND")
		)
		(pad "C34" smd circle
			(at 10.750042 3.420364)
			(size 0.3048 0.3048)
			(layers "F.Cu" "F.Mask" "F.Paste")
			(net "NCF_CPU0_P0_GND")
		)
		(pad "CA7" smd circle
			(at 0.80264 -2.12471)
			(size 0.381 0.381)
			(layers "F.Cu" "F.Mask" "F.Paste")
			(net "P5E_CPU0_P0_TX_BUF_DP<8>")
		)
		(pad "CA26" smd circle
			(at 0.80264 1.339342)
			(size 0.381 0.381)
			(layers "F.Cu" "F.Mask" "F.Paste")
			(net "P5E_CPU0_P0_RX_DP<8>")
		)
		(pad "CB2" smd circle
			(at 0.54991 -3.41884)
			(size 0.3048 0.3048)
			(layers "F.Cu" "F.Mask" "F.Paste")
			(net "P5E_CPU0_P0_RX_BUF_DN<8>")
		)
		(pad "CB34" smd circle
			(at 0.54991 3.420364)
			(size 0.3048 0.3048)
			(layers "F.Cu" "F.Mask" "F.Paste")
			(net "P5E_CPU0_P0_TX_C_DN<8>")
		)
		(pad "CC10" smd circle
			(at 0.40259 -1.431798)
			(size 0.381 0.381)
			(layers "F.Cu" "F.Mask" "F.Paste")
			(net "P5E_CPU0_P0_TX_BUF_DN<8>")
		)
		(pad "CC29" smd circle
			(at 0.40259 2.032254)
			(size 0.381 0.381)
			(layers "F.Cu" "F.Mask" "F.Paste")
			(net "P5E_CPU0_P0_RX_DN<8>")
		)
		(pad "CD1" smd oval
			(at 0.249936 -3.938524)
			(size 0.254 0.3302)
			(layers "F.Cu" "F.Mask" "F.Paste")
			(net "P5E_CPU0_P0_RX_BUF_DP<8>")
		)
		(pad "CD35" smd oval
			(at 0.249936 3.940048)
			(size 0.254 0.3302)
			(layers "F.Cu" "F.Mask" "F.Paste")
			(net "P5E_CPU0_P0_TX_C_DP<8>")
		)
		(pad "CE4" smd circle
			(at 0.00254 -2.817368)
			(size 0.381 0.381)
			(layers "F.Cu" "F.Mask" "F.Paste")
			(net "GND")
		)
		(pad "CE13" smd circle
			(at 0.00254 -0.79629)
			(size 0.3048 0.3048)
			(layers "F.Cu" "F.Mask" "F.Paste")
			(net "GND")
		)
		(pad "CE17" smd circle
			(at 0.00254 -0.296164)
			(size 0.3048 0.3048)
			(layers "F.Cu" "F.Mask" "F.Paste")
			(net "P1V8_CPU0_RT0_1A")
		)
		(pad "CE20" smd circle
			(at 0.00254 0.203708)
			(size 0.3048 0.3048)
			(layers "F.Cu" "F.Mask" "F.Paste")
			(net "P1V8_CPU0_RT0_1A")
		)
		(pad "CE22" smd circle
			(at 0.00254 0.703834)
			(size 0.3048 0.3048)
			(layers "F.Cu" "F.Mask" "F.Paste")
			(net "GND")
		)
		(pad "CE32" smd circle
			(at 0.00254 2.724912)
			(size 0.381 0.381)
			(layers "F.Cu" "F.Mask" "F.Paste")
			(net "GND")
		)
		(pad "CF2" smd circle
			(at -0.050038 -3.41884)
			(size 0.3048 0.3048)
			(layers "F.Cu" "F.Mask" "F.Paste")
			(net "GND")
		)
		(pad "CF34" smd circle
			(at -0.050038 3.420364)
			(size 0.3048 0.3048)
			(layers "F.Cu" "F.Mask" "F.Paste")
			(net "GND")
		)
		(pad "CG1" smd oval
			(at -0.350012 -3.938524)
			(size 0.254 0.3302)
			(layers "F.Cu" "F.Mask" "F.Paste")
			(net "GND")
		)
		(pad "CG35" smd oval
			(at -0.350012 3.940048)
			(size 0.254 0.3302)
			(layers "F.Cu" "F.Mask" "F.Paste")
			(net "GND")
		)
		(pad "CH7" smd circle
			(at -0.39751 -2.12471)
			(size 0.381 0.381)
			(layers "F.Cu" "F.Mask" "F.Paste")
			(net "P5E_CPU0_P0_TX_BUF_DP<7>")
		)
		(pad "CH26" smd circle
			(at -0.39751 1.339342)
			(size 0.381 0.381)
			(layers "F.Cu" "F.Mask" "F.Paste")
			(net "P5E_CPU0_P0_RX_DP<7>")
		)
		(pad "CJ2" smd circle
			(at -0.649986 -3.41884)
			(size 0.3048 0.3048)
			(layers "F.Cu" "F.Mask" "F.Paste")
			(net "P5E_CPU0_P0_RX_BUF_DN<7>")
		)
		(pad "CJ34" smd circle
			(at -0.649986 3.420364)
			(size 0.3048 0.3048)
			(layers "F.Cu" "F.Mask" "F.Paste")
			(net "P5E_CPU0_P0_TX_C_DN<7>")
		)
		(pad "CK10" smd circle
			(at -0.797306 -1.431798)
			(size 0.381 0.381)
			(layers "F.Cu" "F.Mask" "F.Paste")
			(net "P5E_CPU0_P0_TX_BUF_DN<7>")
		)
		(pad "CK29" smd circle
			(at -0.797306 2.032254)
			(size 0.381 0.381)
			(layers "F.Cu" "F.Mask" "F.Paste")
			(net "P5E_CPU0_P0_RX_DN<7>")
		)
		(pad "CL1" smd oval
			(at -0.94996 -3.938524)
			(size 0.254 0.3302)
			(layers "F.Cu" "F.Mask" "F.Paste")
			(net "P5E_CPU0_P0_RX_BUF_DP<7>")
		)
		(pad "CL35" smd oval
			(at -0.94996 3.940048)
			(size 0.254 0.3302)
			(layers "F.Cu" "F.Mask" "F.Paste")
			(net "P5E_CPU0_P0_TX_C_DP<7>")
		)
		(pad "CM4" smd circle
			(at -1.197356 -2.817368)
			(size 0.381 0.381)
			(layers "F.Cu" "F.Mask" "F.Paste")
			(net "GND")
		)
		(pad "CM13" smd circle
			(at -1.197356 -0.79629)
			(size 0.3048 0.3048)
			(layers "F.Cu" "F.Mask" "F.Paste")
			(net "GND")
		)
		(pad "CM17" smd circle
			(at -1.197356 -0.296164)
			(size 0.3048 0.3048)
			(layers "F.Cu" "F.Mask" "F.Paste")
			(net "P1V8_CPU0_RT0_1A")
		)
		(pad "CM20" smd circle
			(at -1.197356 0.203708)
			(size 0.3048 0.3048)
			(layers "F.Cu" "F.Mask" "F.Paste")
			(net "P1V8_CPU0_RT0_1A")
		)
		(pad "CM22" smd circle
			(at -1.197356 0.703834)
			(size 0.3048 0.3048)
			(layers "F.Cu" "F.Mask" "F.Paste")
			(net "GND")
		)
		(pad "CM32" smd circle
			(at -1.197356 2.724912)
			(size 0.381 0.381)
			(layers "F.Cu" "F.Mask" "F.Paste")
			(net "GND")
		)
		(pad "CN2" smd circle
			(at -1.249934 -3.41884)
			(size 0.3048 0.3048)
			(layers "F.Cu" "F.Mask" "F.Paste")
			(net "GND")
		)
		(pad "CN34" smd circle
			(at -1.249934 3.420364)
			(size 0.3048 0.3048)
			(layers "F.Cu" "F.Mask" "F.Paste")
			(net "GND")
		)
		(pad "CP1" smd oval
			(at -1.549908 -3.938524)
			(size 0.254 0.3302)
			(layers "F.Cu" "F.Mask" "F.Paste")
			(net "GND")
		)
		(pad "CP35" smd oval
			(at -1.549908 3.940048)
			(size 0.254 0.3302)
			(layers "F.Cu" "F.Mask" "F.Paste")
			(net "GND")
		)
		(pad "CR7" smd circle
			(at -1.597406 -2.12471)
			(size 0.381 0.381)
			(layers "F.Cu" "F.Mask" "F.Paste")
			(net "P5E_CPU0_P0_TX_BUF_DP<6>")
		)
		(pad "CR26" smd circle
			(at -1.597406 1.339342)
			(size 0.381 0.381)
			(layers "F.Cu" "F.Mask" "F.Paste")
			(net "P5E_CPU0_P0_RX_DP<6>")
		)
		(pad "CT2" smd circle
			(at -1.849882 -3.41884)
			(size 0.3048 0.3048)
			(layers "F.Cu" "F.Mask" "F.Paste")
			(net "P5E_CPU0_P0_RX_BUF_DN<6>")
		)
		(pad "CT34" smd circle
			(at -1.849882 3.420364)
			(size 0.3048 0.3048)
			(layers "F.Cu" "F.Mask" "F.Paste")
			(net "P5E_CPU0_P0_TX_C_DN<6>")
		)
		(pad "CU10" smd circle
			(at -1.997456 -1.431798)
			(size 0.381 0.381)
			(layers "F.Cu" "F.Mask" "F.Paste")
			(net "P5E_CPU0_P0_TX_BUF_DN<6>")
		)
		(pad "CU29" smd circle
			(at -1.997456 2.032254)
			(size 0.381 0.381)
			(layers "F.Cu" "F.Mask" "F.Paste")
			(net "P5E_CPU0_P0_RX_DN<6>")
		)
		(pad "CV1" smd oval
			(at -2.15011 -3.938524)
			(size 0.254 0.3302)
			(layers "F.Cu" "F.Mask" "F.Paste")
			(net "P5E_CPU0_P0_RX_BUF_DP<6>")
		)
		(pad "CV35" smd oval
			(at -2.15011 3.940048)
			(size 0.254 0.3302)
			(layers "F.Cu" "F.Mask" "F.Paste")
			(net "P5E_CPU0_P0_TX_C_DP<6>")
		)
		(pad "CW4" smd circle
			(at -2.397506 -2.817368)
			(size 0.381 0.381)
			(layers "F.Cu" "F.Mask" "F.Paste")
			(net "GND")
		)
		(pad "CW13" smd circle
			(at -2.397506 -0.79629)
			(size 0.3048 0.3048)
			(layers "F.Cu" "F.Mask" "F.Paste")
			(net "GND")
		)
		(pad "CW17" smd circle
			(at -2.397506 -0.296164)
			(size 0.3048 0.3048)
			(layers "F.Cu" "F.Mask" "F.Paste")
			(net "P0V9_CPU0_RT_2D")
		)
		(pad "CW20" smd circle
			(at -2.397506 0.203708)
			(size 0.3048 0.3048)
			(layers "F.Cu" "F.Mask" "F.Paste")
			(net "P0V9_CPU0_RT_2D")
		)
		(pad "CW22" smd circle
			(at -2.397506 0.703834)
			(size 0.3048 0.3048)
			(layers "F.Cu" "F.Mask" "F.Paste")
			(net "GND")
		)
		(pad "CW32" smd circle
			(at -2.397506 2.724912)
			(size 0.381 0.381)
			(layers "F.Cu" "F.Mask" "F.Paste")
			(net "GND")
		)
		(pad "CY2" smd circle
			(at -2.450084 -3.41884)
			(size 0.3048 0.3048)
			(layers "F.Cu" "F.Mask" "F.Paste")
			(net "GND")
		)
		(pad "CY34" smd circle
			(at -2.450084 3.420364)
			(size 0.3048 0.3048)
			(layers "F.Cu" "F.Mask" "F.Paste")
			(net "GND")
		)
		(pad "D1" smd oval
			(at 10.450068 -3.938524)
			(size 0.254 0.3302)
			(layers "F.Cu" "F.Mask" "F.Paste")
			(net "NCF_CPU0_P0_GND")
		)
		(pad "D35" smd oval
			(at 10.450068 3.940048)
			(size 0.254 0.3302)
			(layers "F.Cu" "F.Mask" "F.Paste")
			(net "NCF_CPU0_P0_GND")
		)
		(pad "DA1" smd oval
			(at -2.750058 -3.938524)
			(size 0.254 0.3302)
			(layers "F.Cu" "F.Mask" "F.Paste")
			(net "GND")
		)
		(pad "DA35" smd oval
			(at -2.750058 3.940048)
			(size 0.254 0.3302)
			(layers "F.Cu" "F.Mask" "F.Paste")
			(net "GND")
		)
		(pad "DB7" smd circle
			(at -2.797302 -2.12471)
			(size 0.381 0.381)
			(layers "F.Cu" "F.Mask" "F.Paste")
			(net "P5E_CPU0_P0_TX_BUF_DP<5>")
		)
		(pad "DB26" smd circle
			(at -2.797302 1.339342)
			(size 0.381 0.381)
			(layers "F.Cu" "F.Mask" "F.Paste")
			(net "P5E_CPU0_P0_RX_DP<5>")
		)
		(pad "DC2" smd circle
			(at -3.050032 -3.41884)
			(size 0.3048 0.3048)
			(layers "F.Cu" "F.Mask" "F.Paste")
			(net "P5E_CPU0_P0_RX_BUF_DN<5>")
		)
		(pad "DC34" smd circle
			(at -3.050032 3.420364)
			(size 0.3048 0.3048)
			(layers "F.Cu" "F.Mask" "F.Paste")
			(net "P5E_CPU0_P0_TX_C_DN<5>")
		)
		(pad "DD10" smd circle
			(at -3.197352 -1.431798)
			(size 0.381 0.381)
			(layers "F.Cu" "F.Mask" "F.Paste")
			(net "P5E_CPU0_P0_TX_BUF_DN<5>")
		)
		(pad "DD29" smd circle
			(at -3.197352 2.032254)
			(size 0.381 0.381)
			(layers "F.Cu" "F.Mask" "F.Paste")
			(net "P5E_CPU0_P0_RX_DN<5>")
		)
		(pad "DE1" smd oval
			(at -3.350006 -3.938524)
			(size 0.254 0.3302)
			(layers "F.Cu" "F.Mask" "F.Paste")
			(net "P5E_CPU0_P0_RX_BUF_DP<5>")
		)
		(pad "DE35" smd oval
			(at -3.350006 3.940048)
			(size 0.254 0.3302)
			(layers "F.Cu" "F.Mask" "F.Paste")
			(net "P5E_CPU0_P0_TX_C_DP<5>")
		)
		(pad "DF4" smd circle
			(at -3.597402 -2.817368)
			(size 0.381 0.381)
			(layers "F.Cu" "F.Mask" "F.Paste")
			(net "GND")
		)
		(pad "DF13" smd circle
			(at -3.597402 -0.79629)
			(size 0.3048 0.3048)
			(layers "F.Cu" "F.Mask" "F.Paste")
			(net "GND")
		)
		(pad "DF17" smd circle
			(at -3.597402 -0.296164)
			(size 0.3048 0.3048)
			(layers "F.Cu" "F.Mask" "F.Paste")
			(net "P0V9_CPU0_RT0_2A_2D")
		)
		(pad "DF20" smd circle
			(at -3.597402 0.203708)
			(size 0.3048 0.3048)
			(layers "F.Cu" "F.Mask" "F.Paste")
			(net "P0V9_CPU0_RT0_2A_2D")
		)
		(pad "DF22" smd circle
			(at -3.597402 0.703834)
			(size 0.3048 0.3048)
			(layers "F.Cu" "F.Mask" "F.Paste")
			(net "GND")
		)
		(pad "DF32" smd circle
			(at -3.597402 2.724912)
			(size 0.381 0.381)
			(layers "F.Cu" "F.Mask" "F.Paste")
			(net "GND")
		)
		(pad "DG2" smd circle
			(at -3.64998 -3.41884)
			(size 0.3048 0.3048)
			(layers "F.Cu" "F.Mask" "F.Paste")
			(net "GND")
		)
		(pad "DG34" smd circle
			(at -3.64998 3.420364)
			(size 0.3048 0.3048)
			(layers "F.Cu" "F.Mask" "F.Paste")
			(net "GND")
		)
		(pad "DH1" smd oval
			(at -3.949954 -3.938524)
			(size 0.254 0.3302)
			(layers "F.Cu" "F.Mask" "F.Paste")
			(net "GND")
		)
		(pad "DH35" smd oval
			(at -3.949954 3.940048)
			(size 0.254 0.3302)
			(layers "F.Cu" "F.Mask" "F.Paste")
			(net "GND")
		)
		(pad "DJ7" smd circle
			(at -3.997452 -2.12471)
			(size 0.381 0.381)
			(layers "F.Cu" "F.Mask" "F.Paste")
			(net "P5E_CPU0_P0_TX_BUF_DP<4>")
		)
		(pad "DJ26" smd circle
			(at -3.997452 1.339342)
			(size 0.381 0.381)
			(layers "F.Cu" "F.Mask" "F.Paste")
			(net "P5E_CPU0_P0_RX_DP<4>")
		)
		(pad "DK2" smd circle
			(at -4.249928 -3.41884)
			(size 0.3048 0.3048)
			(layers "F.Cu" "F.Mask" "F.Paste")
			(net "P5E_CPU0_P0_RX_BUF_DN<4>")
		)
		(pad "DK34" smd circle
			(at -4.249928 3.420364)
			(size 0.3048 0.3048)
			(layers "F.Cu" "F.Mask" "F.Paste")
			(net "P5E_CPU0_P0_TX_C_DN<4>")
		)
		(pad "DL10" smd circle
			(at -4.397502 -1.431798)
			(size 0.381 0.381)
			(layers "F.Cu" "F.Mask" "F.Paste")
			(net "P5E_CPU0_P0_TX_BUF_DN<4>")
		)
		(pad "DL29" smd circle
			(at -4.397502 2.032254)
			(size 0.381 0.381)
			(layers "F.Cu" "F.Mask" "F.Paste")
			(net "P5E_CPU0_P0_RX_DN<4>")
		)
		(pad "DM1" smd oval
			(at -4.549902 -3.938524)
			(size 0.254 0.3302)
			(layers "F.Cu" "F.Mask" "F.Paste")
			(net "P5E_CPU0_P0_RX_BUF_DP<4>")
		)
		(pad "DM35" smd oval
			(at -4.549902 3.940048)
			(size 0.254 0.3302)
			(layers "F.Cu" "F.Mask" "F.Paste")
			(net "P5E_CPU0_P0_TX_C_DP<4>")
		)
		(pad "DN4" smd circle
			(at -4.797298 -2.817368)
			(size 0.381 0.381)
			(layers "F.Cu" "F.Mask" "F.Paste")
			(net "GND")
		)
		(pad "DN13" smd circle
			(at -4.797298 -0.79629)
			(size 0.3048 0.3048)
			(layers "F.Cu" "F.Mask" "F.Paste")
			(net "GND")
		)
		(pad "DN17" smd circle
			(at -4.797298 -0.296164)
			(size 0.3048 0.3048)
			(layers "F.Cu" "F.Mask" "F.Paste")
			(net "P0V9_CPU0_RT0_2A")
		)
		(pad "DN20" smd circle
			(at -4.797298 0.203708)
			(size 0.3048 0.3048)
			(layers "F.Cu" "F.Mask" "F.Paste")
			(net "P0V9_CPU0_RT0_2A")
		)
		(pad "DN22" smd circle
			(at -4.797298 0.703834)
			(size 0.3048 0.3048)
			(layers "F.Cu" "F.Mask" "F.Paste")
			(net "GND")
		)
		(pad "DN32" smd circle
			(at -4.797298 2.724912)
			(size 0.381 0.381)
			(layers "F.Cu" "F.Mask" "F.Paste")
			(net "GND")
		)
		(pad "DP2" smd circle
			(at -4.849876 -3.41884)
			(size 0.3048 0.3048)
			(layers "F.Cu" "F.Mask" "F.Paste")
			(net "GND")
		)
		(pad "DP34" smd circle
			(at -4.849876 3.420364)
			(size 0.3048 0.3048)
			(layers "F.Cu" "F.Mask" "F.Paste")
			(net "GND")
		)
		(pad "DR1" smd oval
			(at -5.150104 -3.938524)
			(size 0.254 0.3302)
			(layers "F.Cu" "F.Mask" "F.Paste")
			(net "GND")
		)
		(pad "DR35" smd oval
			(at -5.150104 3.940048)
			(size 0.254 0.3302)
			(layers "F.Cu" "F.Mask" "F.Paste")
			(net "GND")
		)
		(pad "DT7" smd circle
			(at -5.197348 -2.12471)
			(size 0.381 0.381)
			(layers "F.Cu" "F.Mask" "F.Paste")
			(net "P5E_CPU0_P0_TX_BUF_DP<3>")
		)
		(pad "DT26" smd circle
			(at -5.197348 1.339342)
			(size 0.381 0.381)
			(layers "F.Cu" "F.Mask" "F.Paste")
			(net "P5E_CPU0_P0_RX_DP<3>")
		)
		(pad "DU2" smd circle
			(at -5.450078 -3.41884)
			(size 0.3048 0.3048)
			(layers "F.Cu" "F.Mask" "F.Paste")
			(net "P5E_CPU0_P0_RX_BUF_DN<3>")
		)
		(pad "DU34" smd circle
			(at -5.450078 3.420364)
			(size 0.3048 0.3048)
			(layers "F.Cu" "F.Mask" "F.Paste")
			(net "P5E_CPU0_P0_TX_C_DN<3>")
		)
		(pad "DV10" smd circle
			(at -5.597398 -1.431798)
			(size 0.381 0.381)
			(layers "F.Cu" "F.Mask" "F.Paste")
			(net "P5E_CPU0_P0_TX_BUF_DN<3>")
		)
		(pad "DV29" smd circle
			(at -5.597398 2.032254)
			(size 0.381 0.381)
			(layers "F.Cu" "F.Mask" "F.Paste")
			(net "P5E_CPU0_P0_RX_DN<3>")
		)
		(pad "DW1" smd oval
			(at -5.750052 -3.938524)
			(size 0.254 0.3302)
			(layers "F.Cu" "F.Mask" "F.Paste")
			(net "P5E_CPU0_P0_RX_BUF_DP<3>")
		)
		(pad "DW35" smd oval
			(at -5.750052 3.940048)
			(size 0.254 0.3302)
			(layers "F.Cu" "F.Mask" "F.Paste")
			(net "P5E_CPU0_P0_TX_C_DP<3>")
		)
		(pad "DY4" smd circle
			(at -5.997448 -2.817368)
			(size 0.381 0.381)
			(layers "F.Cu" "F.Mask" "F.Paste")
			(net "GND")
		)
		(pad "DY13" smd circle
			(at -5.997448 -0.79629)
			(size 0.3048 0.3048)
			(layers "F.Cu" "F.Mask" "F.Paste")
			(net "GND")
		)
		(pad "DY17" smd circle
			(at -5.997448 -0.296164)
			(size 0.3048 0.3048)
			(layers "F.Cu" "F.Mask" "F.Paste")
			(net "P0V9_CPU0_RT0_2A")
		)
		(pad "DY20" smd circle
			(at -5.997448 0.203708)
			(size 0.3048 0.3048)
			(layers "F.Cu" "F.Mask" "F.Paste")
			(net "P0V9_CPU0_RT0_2A")
		)
		(pad "DY22" smd circle
			(at -5.997448 0.703834)
			(size 0.3048 0.3048)
			(layers "F.Cu" "F.Mask" "F.Paste")
			(net "GND")
		)
	)
)
